(kicad_pcb
	(version 20260206)
	(generator "pcbnew")
	(generator_version "10.0")
	(general
		(thickness 1.6)
		(legacy_teardrops no)
	)
	(paper "A4")
	(title_block
		(title "Wiwynn_Tioga_Pass_MB.brd")
		(comment 1 "Tioga Pass / footprint 190 of 4770 (U2D1), pads 1645-1752 of 3647")
	)
	(layers
		(0 "F.Cu" signal "TOP")
		(4 "In1.Cu" signal "L2GND")
		(6 "In2.Cu" signal "L3")
		(8 "In3.Cu" signal "L4GND")
		(10 "In4.Cu" signal "L5")
		(12 "In5.Cu" signal "L6GND")
		(14 "In6.Cu" signal "L7VCC")
		(16 "In7.Cu" signal "L8VCC")
		(18 "In8.Cu" signal "L9GND")
		(20 "In9.Cu" signal "L10")
		(22 "In10.Cu" signal "L11GND")
		(24 "In11.Cu" signal "L12")
		(26 "In12.Cu" signal "L13GND")
		(2 "B.Cu" signal "BOTTOM")
		(9 "F.Adhes" user "F.Adhesive")
		(11 "B.Adhes" user "B.Adhesive")
		(13 "F.Paste" user "Package Geometry/Pastemask Top")
		(15 "B.Paste" user "Package Geometry/Pastemask Bottom")
		(5 "F.SilkS" user "Ref Des/Silkscreen Top")
		(7 "B.SilkS" user "Ref Des/Silkscreen Bottom")
		(1 "F.Mask" user "Board Geometry/Soldermask Top")
		(3 "B.Mask" user "Board Geometry/Soldermask Bottom")
		(17 "Dwgs.User" user "User.Drawings")
		(19 "Cmts.User" user "User.Comments")
		(21 "Eco1.User" user "User.Eco1")
		(23 "Eco2.User" user "User.Eco2")
		(25 "Edge.Cuts" user "Board Geometry/Outline")
		(27 "Margin" user)
		(31 "F.CrtYd" user "Package Geometry/Place Bound Top")
		(29 "B.CrtYd" user "Package Geometry/Place Bound Bottom")
		(35 "F.Fab" user "Ref Des/Assembly Top")
		(33 "B.Fab" user "Ref Des/Assembly Bottom")
	)
	(footprint ""
		(layer "F.Cu")
		(at 104.99979 -76.550012 180)
		(property "Reference" "U2D1"
			(at 25.19299 30.484318 0)
			(unlocked yes)
			(layer "F.SilkS")
			(effects
				(font
					(size 0.7874 0.5842)
					(thickness 0.1524)
				)
			)
		)
		(property "Value" ""
			(at 0 0 180)
			(layer "F.Fab")
			(effects
				(font
					(size 1.27 1.27)
				)
			)
		)
		(duplicate_pad_numbers_are_jumpers no)
		(pad "CN70" smd circle
			(at 23.514558 8.758428)
			(size 0.4318 0.4318)
			(layers "F.Cu" "F.Mask" "F.Paste")
			(net "M_M_DQS_DN<8>")
		)
		(pad "CN74" smd circle
			(at 26.948384 8.758428)
			(size 0.4318 0.4318)
			(layers "F.Cu" "F.Mask" "F.Paste")
			(net "M_M_DQ<4>")
		)
		(pad "CN76" smd circle
			(at 28.665424 8.758428)
			(size 0.4318 0.4318)
			(layers "F.Cu" "F.Mask" "F.Paste")
			(net "M_M_DQ<1>")
		)
		(pad "CN78" smd circle
			(at 30.382464 8.758428)
			(size 0.4318 0.4318)
			(layers "F.Cu" "F.Mask" "F.Paste")
			(net "GND")
		)
		(pad "CN80" smd circle
			(at 32.099504 8.758428)
			(size 0.4318 0.4318)
			(layers "F.Cu" "F.Mask" "F.Paste")
			(net "M_L_DQS_DN<9>")
		)
		(pad "CN82" smd circle
			(at 33.816544 8.758428)
			(size 0.4318 0.4318)
			(layers "F.Cu" "F.Mask" "F.Paste")
			(net "M_L_DQ<7>")
		)
		(pad "CN84" smd circle
			(at 35.533584 8.758428)
			(size 0.4318 0.4318)
			(layers "F.Cu" "F.Mask" "F.Paste")
			(net "M_K_DQ<0>")
		)
		(pad "CN86" smd custom
			(at 37.250624 8.758428 270)
			(size 0.10795 0.10795)
			(layers "F.Cu" "F.Mask" "F.Paste")
			(net "M_K_DQ<1>")
			(options
				(clearance outline)
				(anchor circle)
			)
			(primitives
				(gr_poly
					(pts
						(arc
							(start 0.2159 -0.0381)
							(mid 0 -0.254)
							(end -0.2159 -0.0381)
						)
						(arc
							(start -0.2159 0.0381)
							(mid 0 0.254)
							(end 0.2159 0.0381)
						)
					)
					(width 0)
					(fill yes)
				)
			)
		)
		(pad "CP1" smd custom
			(at -37.250624 11.053572 90)
			(size 0.10795 0.10795)
			(layers "F.Cu" "F.Mask" "F.Paste")
			(net "GND")
			(options
				(clearance outline)
				(anchor circle)
			)
			(primitives
				(gr_poly
					(pts
						(arc
							(start 0.2159 -0.0381)
							(mid 0 -0.254)
							(end -0.2159 -0.0381)
						)
						(arc
							(start -0.2159 0.0381)
							(mid 0 0.254)
							(end 0.2159 0.0381)
						)
					)
					(width 0)
					(fill yes)
				)
			)
		)
		(pad "CP3" smd circle
			(at -35.533584 11.053572)
			(size 0.4318 0.4318)
			(layers "F.Cu" "F.Mask" "F.Paste")
			(net "TP_P3E_CPU1_PE2_RSR_TXP<3>")
		)
		(pad "CP5" smd circle
			(at -33.816544 11.053572)
			(size 0.4318 0.4318)
			(layers "F.Cu" "F.Mask" "F.Paste")
			(net "TP_CPU1_DMI_TX_DN3")
		)
		(pad "CP7" smd circle
			(at -32.099504 11.053572)
			(size 0.4318 0.4318)
			(layers "F.Cu" "F.Mask" "F.Paste")
			(net "TP_P3E_CPU1_PE2_RSR_RXN<2>")
		)
		(pad "CP9" smd circle
			(at -30.382464 11.053572)
			(size 0.4318 0.4318)
			(layers "F.Cu" "F.Mask" "F.Paste")
			(net "TP_P3E_CPU1_PE2_RSR_RXN<1>")
		)
		(pad "CP11" smd circle
			(at -28.665424 11.053572)
			(size 0.4318 0.4318)
			(layers "F.Cu" "F.Mask" "F.Paste")
			(net "TP_CPU1_DMI_RX_DP2")
		)
		(pad "CP13" smd circle
			(at -26.948384 11.053572)
			(size 0.4318 0.4318)
			(layers "F.Cu" "F.Mask" "F.Paste")
			(net "PVCCIO_CPU1")
		)
		(pad "CP19" smd circle
			(at -21.797518 11.053572)
			(size 0.4318 0.4318)
			(layers "F.Cu" "F.Mask" "F.Paste")
			(net "GND")
		)
		(pad "CP21" smd circle
			(at -20.080478 11.053572)
			(size 0.4318 0.4318)
			(layers "F.Cu" "F.Mask" "F.Paste")
			(net "GND")
		)
		(pad "CP23" smd circle
			(at -18.363438 11.053572)
			(size 0.4318 0.4318)
			(layers "F.Cu" "F.Mask" "F.Paste")
			(net "PVCCMCP_CPU1")
		)
		(pad "CP25" smd circle
			(at -16.646398 11.053572)
			(size 0.4318 0.4318)
			(layers "F.Cu" "F.Mask" "F.Paste")
			(net "GND")
		)
		(pad "CP27" smd circle
			(at -14.929612 11.053572)
			(size 0.4318 0.4318)
			(layers "F.Cu" "F.Mask" "F.Paste")
			(net "CLK_100M_CPU1_BCLK1_DP")
		)
		(pad "CP29" smd circle
			(at -13.212572 11.053572)
			(size 0.4318 0.4318)
			(layers "F.Cu" "F.Mask" "F.Paste")
			(net "A_CPU1_PE3_RBIAS")
		)
		(pad "CP31" smd circle
			(at -11.495532 11.053572)
			(size 0.4318 0.4318)
			(layers "F.Cu" "F.Mask" "F.Paste")
			(net "TP_CPU1_RSVD_73")
		)
		(pad "CP33" smd circle
			(at -9.778492 11.053572)
			(size 0.4318 0.4318)
			(layers "F.Cu" "F.Mask" "F.Paste")
			(net "PVCCIN_CPU1")
		)
		(pad "CP55" smd circle
			(at 10.637012 9.253474)
			(size 0.508 0.508)
			(layers "F.Cu" "F.Mask" "F.Paste")
			(net "PVCCIN_CPU1")
		)
		(pad "CP57" smd circle
			(at 12.354052 9.253474)
			(size 0.4318 0.4318)
			(layers "F.Cu" "F.Mask" "F.Paste")
			(net "PVCCIN_CPU1")
		)
		(pad "CP59" smd circle
			(at 14.071092 9.253474)
			(size 0.4318 0.4318)
			(layers "F.Cu" "F.Mask" "F.Paste")
			(net "GND")
		)
		(pad "CP61" smd circle
			(at 15.787878 9.253474)
			(size 0.4318 0.4318)
			(layers "F.Cu" "F.Mask" "F.Paste")
			(net "M_K_CPU_VREF")
		)
		(pad "CP63" smd circle
			(at 17.504918 9.253474)
			(size 0.4318 0.4318)
			(layers "F.Cu" "F.Mask" "F.Paste")
			(net "M_M_DQ<26>")
		)
		(pad "CP65" smd circle
			(at 19.221958 9.253474)
			(size 0.4318 0.4318)
			(layers "F.Cu" "F.Mask" "F.Paste")
			(net "M_M_DQS_DN<12>")
		)
		(pad "CP67" smd circle
			(at 20.938998 9.253474)
			(size 0.4318 0.4318)
			(layers "F.Cu" "F.Mask" "F.Paste")
			(net "M_M_DQ<28>")
		)
		(pad "CP69" smd circle
			(at 22.656038 9.253474)
			(size 0.4318 0.4318)
			(layers "F.Cu" "F.Mask" "F.Paste")
			(net "GND")
		)
		(pad "CP73" smd circle
			(at 26.090118 9.253474)
			(size 0.4318 0.4318)
			(layers "F.Cu" "F.Mask" "F.Paste")
			(net "GND")
		)
		(pad "CP75" smd circle
			(at 27.806904 9.253474)
			(size 0.4318 0.4318)
			(layers "F.Cu" "F.Mask" "F.Paste")
			(net "GND")
		)
		(pad "CP77" smd circle
			(at 29.523944 9.253474)
			(size 0.4318 0.4318)
			(layers "F.Cu" "F.Mask" "F.Paste")
			(net "M_M_DQS_DN<0>")
		)
		(pad "CP79" smd circle
			(at 31.240984 9.253474)
			(size 0.4318 0.4318)
			(layers "F.Cu" "F.Mask" "F.Paste")
			(net "M_L_DQS_DP<9>")
		)
		(pad "CP81" smd circle
			(at 32.958024 9.253474)
			(size 0.4318 0.4318)
			(layers "F.Cu" "F.Mask" "F.Paste")
			(net "GND")
		)
		(pad "CP83" smd circle
			(at 34.675064 9.253474)
			(size 0.4318 0.4318)
			(layers "F.Cu" "F.Mask" "F.Paste")
			(net "GND")
		)
		(pad "CP85" smd circle
			(at 36.392104 9.253474)
			(size 0.4318 0.4318)
			(layers "F.Cu" "F.Mask" "F.Paste")
			(net "M_K_DQS_DP<9>")
		)
		(pad "CR2" smd circle
			(at -36.392104 11.549126)
			(size 0.4318 0.4318)
			(layers "F.Cu" "F.Mask" "F.Paste")
			(net "TP_P3E_CPU1_PE2_RSR_TXP<2>")
		)
		(pad "CR4" smd circle
			(at -34.675064 11.549126)
			(size 0.4318 0.4318)
			(layers "F.Cu" "F.Mask" "F.Paste")
			(net "TP_CPU1_DMI_TX_DP3")
		)
		(pad "CR6" smd circle
			(at -32.958024 11.549126)
			(size 0.4318 0.4318)
			(layers "F.Cu" "F.Mask" "F.Paste")
			(net "GND")
		)
		(pad "CR8" smd circle
			(at -31.240984 11.549126)
			(size 0.4318 0.4318)
			(layers "F.Cu" "F.Mask" "F.Paste")
			(net "TP_P3E_CPU1_PE2_RSR_RXP<0>")
		)
		(pad "CR10" smd circle
			(at -29.523944 11.549126)
			(size 0.4318 0.4318)
			(layers "F.Cu" "F.Mask" "F.Paste")
			(net "GND")
		)
		(pad "CR12" smd circle
			(at -27.806904 11.549126)
			(size 0.4318 0.4318)
			(layers "F.Cu" "F.Mask" "F.Paste")
			(net "TP_CPU1_DMI_RX_DN2")
		)
		(pad "CR14" smd circle
			(at -26.090118 11.549126)
			(size 0.4318 0.4318)
			(layers "F.Cu" "F.Mask" "F.Paste")
			(net "TP_CPU1_UPI2_RSVD_DE16")
		)
		(pad "CR18" smd circle
			(at -22.656038 11.549126)
			(size 0.4318 0.4318)
			(layers "F.Cu" "F.Mask" "F.Paste")
			(net "GND")
		)
		(pad "CR20" smd circle
			(at -20.938998 11.549126)
			(size 0.4318 0.4318)
			(layers "F.Cu" "F.Mask" "F.Paste")
			(net "GND")
		)
		(pad "CR22" smd circle
			(at -19.221958 11.549126)
			(size 0.4318 0.4318)
			(layers "F.Cu" "F.Mask" "F.Paste")
			(net "GND")
		)
		(pad "CR24" smd circle
			(at -17.504918 11.549126)
			(size 0.4318 0.4318)
			(layers "F.Cu" "F.Mask" "F.Paste")
			(net "GND")
		)
		(pad "CR26" smd circle
			(at -15.787878 11.549126)
			(size 0.4318 0.4318)
			(layers "F.Cu" "F.Mask" "F.Paste")
			(net "CLK_100M_CPU1_BCLK1_DN")
		)
		(pad "CR28" smd circle
			(at -14.071092 11.549126)
			(size 0.4318 0.4318)
			(layers "F.Cu" "F.Mask" "F.Paste")
			(net "PWRGD_CPU1_DRAMPWROK_KLM_G")
		)
		(pad "CR30" smd circle
			(at -12.354052 11.549126)
			(size 0.4318 0.4318)
			(layers "F.Cu" "F.Mask" "F.Paste")
			(net "A_CPU1_PE3_RBIAS")
		)
		(pad "CR32" smd circle
			(at -10.637012 11.549126)
			(size 0.4318 0.4318)
			(layers "F.Cu" "F.Mask" "F.Paste")
			(net "GND")
		)
		(pad "CR34" smd circle
			(at -8.919972 11.549126)
			(size 0.4318 0.4318)
			(layers "F.Cu" "F.Mask" "F.Paste")
			(net "PVCCIN_CPU1")
		)
		(pad "CR54" smd circle
			(at 9.778492 9.749028)
			(size 0.508 0.508)
			(layers "F.Cu" "F.Mask" "F.Paste")
			(net "PVCCIN_CPU1")
		)
		(pad "CR56" smd circle
			(at 11.495532 9.749028)
			(size 0.4318 0.4318)
			(layers "F.Cu" "F.Mask" "F.Paste")
			(net "PVCCIN_CPU1")
		)
		(pad "CR58" smd circle
			(at 13.212572 9.749028)
			(size 0.4318 0.4318)
			(layers "F.Cu" "F.Mask" "F.Paste")
			(net "GND")
		)
		(pad "CR60" smd circle
			(at 14.929612 9.749028)
			(size 0.4318 0.4318)
			(layers "F.Cu" "F.Mask" "F.Paste")
			(net "TP_CPU1_RSVD_72")
		)
		(pad "CR62" smd circle
			(at 16.646398 9.749028)
			(size 0.4318 0.4318)
			(layers "F.Cu" "F.Mask" "F.Paste")
			(net "GND")
		)
		(pad "CR64" smd circle
			(at 18.363438 9.749028)
			(size 0.4318 0.4318)
			(layers "F.Cu" "F.Mask" "F.Paste")
			(net "GND")
		)
		(pad "CR66" smd circle
			(at 20.080478 9.749028)
			(size 0.4318 0.4318)
			(layers "F.Cu" "F.Mask" "F.Paste")
			(net "GND")
		)
		(pad "CR68" smd circle
			(at 21.797518 9.749028)
			(size 0.4318 0.4318)
			(layers "F.Cu" "F.Mask" "F.Paste")
			(net "GND")
		)
		(pad "CR74" smd circle
			(at 26.948384 9.749028)
			(size 0.4318 0.4318)
			(layers "F.Cu" "F.Mask" "F.Paste")
			(net "M_M_DQ<0>")
		)
		(pad "CR76" smd circle
			(at 28.665424 9.749028)
			(size 0.4318 0.4318)
			(layers "F.Cu" "F.Mask" "F.Paste")
			(net "M_M_DQS_DP<0>")
		)
		(pad "CR78" smd circle
			(at 30.382464 9.749028)
			(size 0.4318 0.4318)
			(layers "F.Cu" "F.Mask" "F.Paste")
			(net "GND")
		)
		(pad "CR80" smd circle
			(at 32.099504 9.749028)
			(size 0.4318 0.4318)
			(layers "F.Cu" "F.Mask" "F.Paste")
			(net "M_L_DQ<6>")
		)
		(pad "CR82" smd circle
			(at 33.816544 9.749028)
			(size 0.4318 0.4318)
			(layers "F.Cu" "F.Mask" "F.Paste")
			(net "M_L_DQ<3>")
		)
		(pad "CR84" smd circle
			(at 35.533584 9.749028)
			(size 0.4318 0.4318)
			(layers "F.Cu" "F.Mask" "F.Paste")
			(net "M_K_DQS_DN<9>")
		)
		(pad "CR86" smd custom
			(at 37.250624 9.749028 270)
			(size 0.10795 0.10795)
			(layers "F.Cu" "F.Mask" "F.Paste")
			(net "GND")
			(options
				(clearance outline)
				(anchor circle)
			)
			(primitives
				(gr_poly
					(pts
						(arc
							(start 0.2159 -0.0381)
							(mid 0 -0.254)
							(end -0.2159 -0.0381)
						)
						(arc
							(start -0.2159 0.0381)
							(mid 0 0.254)
							(end 0.2159 0.0381)
						)
					)
					(width 0)
					(fill yes)
				)
			)
		)
		(pad "CT1" smd custom
			(at -37.250624 12.044172 90)
			(size 0.10795 0.10795)
			(layers "F.Cu" "F.Mask" "F.Paste")
			(net "TP_P3E_CPU1_PE2_RSR_TXN<2>")
			(options
				(clearance outline)
				(anchor circle)
			)
			(primitives
				(gr_poly
					(pts
						(arc
							(start 0.2159 -0.0381)
							(mid 0 -0.254)
							(end -0.2159 -0.0381)
						)
						(arc
							(start -0.2159 0.0381)
							(mid 0 0.254)
							(end 0.2159 0.0381)
						)
					)
					(width 0)
					(fill yes)
				)
			)
		)
		(pad "CT3" smd circle
			(at -35.533584 12.044172)
			(size 0.4318 0.4318)
			(layers "F.Cu" "F.Mask" "F.Paste")
			(net "TP_P3E_CPU1_PE2_RSR_TXN<3>")
		)
		(pad "CT5" smd circle
			(at -33.816544 12.044172)
			(size 0.4318 0.4318)
			(layers "F.Cu" "F.Mask" "F.Paste")
			(net "TP_CPU1_RSVD_70")
		)
		(pad "CT7" smd circle
			(at -32.099504 12.044172)
			(size 0.4318 0.4318)
			(layers "F.Cu" "F.Mask" "F.Paste")
			(net "GND")
		)
		(pad "CT9" smd circle
			(at -30.382464 12.044172)
			(size 0.4318 0.4318)
			(layers "F.Cu" "F.Mask" "F.Paste")
			(net "TP_P3E_CPU1_PE2_RSR_RXN<0>")
		)
		(pad "CT11" smd circle
			(at -28.665424 12.044172)
			(size 0.4318 0.4318)
			(layers "F.Cu" "F.Mask" "F.Paste")
			(net "TP_CPU1_DMI_RX_DN3")
		)
		(pad "CT13" smd circle
			(at -26.948384 12.044172)
			(size 0.4318 0.4318)
			(layers "F.Cu" "F.Mask" "F.Paste")
			(net "GND")
		)
		(pad "CT19" smd circle
			(at -21.797518 12.044172)
			(size 0.4318 0.4318)
			(layers "F.Cu" "F.Mask" "F.Paste")
			(net "GND")
		)
		(pad "CT21" smd circle
			(at -20.080478 12.044172)
			(size 0.4318 0.4318)
			(layers "F.Cu" "F.Mask" "F.Paste")
			(net "GND")
		)
		(pad "CT23" smd circle
			(at -18.363438 12.044172)
			(size 0.4318 0.4318)
			(layers "F.Cu" "F.Mask" "F.Paste")
			(net "PVCCMCP_CPU1")
		)
		(pad "CT25" smd circle
			(at -16.646398 12.044172)
			(size 0.4318 0.4318)
			(layers "F.Cu" "F.Mask" "F.Paste")
			(net "CLK_100M_CPU1_BCLK2_DN")
		)
		(pad "CT27" smd circle
			(at -14.929612 12.044172)
			(size 0.4318 0.4318)
			(layers "F.Cu" "F.Mask" "F.Paste")
			(net "GND")
		)
		(pad "CT29" smd circle
			(at -13.212572 12.044172)
			(size 0.4318 0.4318)
			(layers "F.Cu" "F.Mask" "F.Paste")
			(net "GND")
		)
		(pad "CT31" smd circle
			(at -11.495532 12.044172)
			(size 0.4318 0.4318)
			(layers "F.Cu" "F.Mask" "F.Paste")
			(net "A_CPU1_MCP01_RBIAS")
		)
		(pad "CT33" smd circle
			(at -9.778492 12.044172)
			(size 0.4318 0.4318)
			(layers "F.Cu" "F.Mask" "F.Paste")
			(net "GND")
		)
		(pad "CT35" smd circle
			(at -8.061452 12.044172)
			(size 0.4318 0.4318)
			(layers "F.Cu" "F.Mask" "F.Paste")
			(net "GND")
		)
		(pad "CT37" smd circle
			(at -6.344412 12.044172)
			(size 0.4318 0.4318)
			(layers "F.Cu" "F.Mask" "F.Paste")
			(net "PVCCIN_CPU1")
		)
		(pad "CT39" smd circle
			(at -4.627626 12.044172)
			(size 0.4318 0.4318)
			(layers "F.Cu" "F.Mask" "F.Paste")
			(net "PVCCIN_CPU1")
		)
		(pad "CT41" smd circle
			(at -2.910586 12.044172)
			(size 0.4318 0.4318)
			(layers "F.Cu" "F.Mask" "F.Paste")
			(net "PVCCIN_CPU1")
		)
		(pad "CT53" smd circle
			(at 8.919972 10.244074)
			(size 0.508 0.508)
			(layers "F.Cu" "F.Mask" "F.Paste")
			(net "PVCCIN_CPU1")
		)
		(pad "CT55" smd circle
			(at 10.637012 10.244074)
			(size 0.4318 0.4318)
			(layers "F.Cu" "F.Mask" "F.Paste")
			(net "PVCCIN_CPU1")
		)
		(pad "CT57" smd circle
			(at 12.354052 10.244074)
			(size 0.4318 0.4318)
			(layers "F.Cu" "F.Mask" "F.Paste")
			(net "GND")
		)
		(pad "CT59" smd circle
			(at 14.071092 10.244074)
			(size 0.4318 0.4318)
			(layers "F.Cu" "F.Mask" "F.Paste")
			(net "SMB_PIROM_CPU1_SCL")
		)
		(pad "CT61" smd circle
			(at 15.787878 10.244074)
			(size 0.4318 0.4318)
			(layers "F.Cu" "F.Mask" "F.Paste")
			(net "M_L_CPU_VREF")
		)
		(pad "CT63" smd circle
			(at 17.504918 10.244074)
			(size 0.4318 0.4318)
			(layers "F.Cu" "F.Mask" "F.Paste")
			(net "M_M_DQ<27>")
		)
		(pad "CT65" smd circle
			(at 19.221958 10.244074)
			(size 0.4318 0.4318)
			(layers "F.Cu" "F.Mask" "F.Paste")
			(net "M_M_DQS_DP<3>")
		)
		(pad "CT67" smd circle
			(at 20.938998 10.244074)
			(size 0.4318 0.4318)
			(layers "F.Cu" "F.Mask" "F.Paste")
			(net "M_M_DQ<29>")
		)
		(pad "CT69" smd circle
			(at 22.656038 10.244074)
			(size 0.4318 0.4318)
			(layers "F.Cu" "F.Mask" "F.Paste")
			(net "TP_CPU1_RSVD_69")
		)
		(pad "CT73" smd circle
			(at 26.090118 10.244074)
			(size 0.4318 0.4318)
			(layers "F.Cu" "F.Mask" "F.Paste")
			(net "GND")
		)
		(pad "CT75" smd circle
			(at 27.806904 10.244074)
			(size 0.4318 0.4318)
			(layers "F.Cu" "F.Mask" "F.Paste")
			(net "M_M_DQS_DN<9>")
		)
		(pad "CT77" smd circle
			(at 29.523944 10.244074)
			(size 0.4318 0.4318)
			(layers "F.Cu" "F.Mask" "F.Paste")
			(net "M_M_DQ<7>")
		)
		(pad "CT79" smd circle
			(at 31.240984 10.244074)
			(size 0.4318 0.4318)
			(layers "F.Cu" "F.Mask" "F.Paste")
			(net "GND")
		)
		(pad "CT81" smd circle
			(at 32.958024 10.244074)
			(size 0.4318 0.4318)
			(layers "F.Cu" "F.Mask" "F.Paste")
			(net "M_L_DQ<2>")
		)
		(pad "CT83" smd circle
			(at 34.675064 10.244074)
			(size 0.4318 0.4318)
			(layers "F.Cu" "F.Mask" "F.Paste")
			(net "GND")
		)
		(pad "CT85" smd circle
			(at 36.392104 10.244074)
			(size 0.4318 0.4318)
			(layers "F.Cu" "F.Mask" "F.Paste")
			(net "GND")
		)
		(pad "CU2" smd circle
			(at -36.392104 12.539726)
			(size 0.4318 0.4318)
			(layers "F.Cu" "F.Mask" "F.Paste")
			(net "TP_P3E_CPU1_PE2_RSR_TXP<1>")
		)
		(pad "CU4" smd circle
			(at -34.675064 12.539726)
			(size 0.4318 0.4318)
			(layers "F.Cu" "F.Mask" "F.Paste")
			(net "GND")
		)
		(pad "CU6" smd circle
			(at -32.958024 12.539726)
			(size 0.4318 0.4318)
			(layers "F.Cu" "F.Mask" "F.Paste")
			(net "TP_CPU1_RSVD_67")
		)
		(pad "CU8" smd circle
			(at -31.240984 12.539726)
			(size 0.4318 0.4318)
			(layers "F.Cu" "F.Mask" "F.Paste")
			(net "TP_P3E_CPU1_PE1_MP_RXP<0>")
		)
	)
)
